(kicad_pcb
	(version 20260206)
	(generator "pcbnew")
	(generator_version "10.0")
	(general
		(thickness 1.6)
		(legacy_teardrops no)
	)
	(paper "A4")
	(title_block
		(title "Wiwynn_Tioga_Pass_MB.brd")
		(comment 1 "Tioga Pass / footprint 2141 of 4770 (J1G2), pads 1-123 of 291")
	)
	(layers
		(0 "F.Cu" signal "TOP")
		(4 "In1.Cu" signal "L2GND")
		(6 "In2.Cu" signal "L3")
		(8 "In3.Cu" signal "L4GND")
		(10 "In4.Cu" signal "L5")
		(12 "In5.Cu" signal "L6GND")
		(14 "In6.Cu" signal "L7VCC")
		(16 "In7.Cu" signal "L8VCC")
		(18 "In8.Cu" signal "L9GND")
		(20 "In9.Cu" signal "L10")
		(22 "In10.Cu" signal "L11GND")
		(24 "In11.Cu" signal "L12")
		(26 "In12.Cu" signal "L13GND")
		(2 "B.Cu" signal "BOTTOM")
		(9 "F.Adhes" user "F.Adhesive")
		(11 "B.Adhes" user "B.Adhesive")
		(13 "F.Paste" user "Package Geometry/Pastemask Top")
		(15 "B.Paste" user "Package Geometry/Pastemask Bottom")
		(5 "F.SilkS" user "Ref Des/Silkscreen Top")
		(7 "B.SilkS" user "Ref Des/Silkscreen Bottom")
		(1 "F.Mask" user "Board Geometry/Soldermask Top")
		(3 "B.Mask" user "Board Geometry/Soldermask Bottom")
		(17 "Dwgs.User" user "User.Drawings")
		(19 "Cmts.User" user "User.Comments")
		(21 "Eco1.User" user "User.Eco1")
		(23 "Eco2.User" user "User.Eco2")
		(25 "Edge.Cuts" user "Board Geometry/Outline")
		(27 "Margin" user)
		(31 "F.CrtYd" user "Package Geometry/Place Bound Top")
		(29 "B.CrtYd" user "Package Geometry/Place Bound Bottom")
		(35 "F.Fab" user "Ref Des/Assembly Top")
		(33 "B.Fab" user "Ref Des/Assembly Bottom")
	)
	(footprint ""
		(layer "F.Cu")
		(at 29.699458 -5.822442 90)
		(property "Reference" "J1G2"
			(at 7.104888 34.562542 0)
			(unlocked yes)
			(layer "F.SilkS")
			(effects
				(font
					(size 0.7874 0.5842)
					(thickness 0.1524)
				)
				(justify left)
			)
		)
		(property "Value" ""
			(at 0 0 90)
			(layer "F.Fab")
			(effects
				(font
					(size 1.27 1.27)
				)
			)
		)
		(duplicate_pad_numbers_are_jumpers no)
		(pad "" thru_hole circle
			(at 2.29997 -5.649976 90)
			(size 2.8194 2.8194)
			(drill 2.4384)
			(layers "*.Cu" "*.Mask")
			(remove_unused_layers no)
			(clearance 0.127)
			(thermal_gap 0.127)
		)
		(pad "" thru_hole oval
			(at 2.29997 68.90004 90)
			(size 2.8194 1.5748)
			(drill oval 2.4384 1.1938)
			(layers "*.Cu" "*.Mask")
			(remove_unused_layers no)
			(clearance 0.127)
			(thermal_gap 0.127)
		)
		(pad "" thru_hole circle
			(at 2.29997 132.299964 90)
			(size 2.8194 2.8194)
			(drill 2.4384)
			(layers "*.Cu" "*.Mask")
			(remove_unused_layers no)
			(clearance 0.127)
			(thermal_gap 0.127)
		)
		(pad "1" smd rect
			(at 0 0 90)
			(size 1.8034 0.508)
			(layers "F.Cu" "F.Mask" "F.Paste")
			(net "P12V_NVDIMM_GHJ")
		)
		(pad "2" smd rect
			(at 0 0.849884 90)
			(size 1.8034 0.508)
			(layers "F.Cu" "F.Mask" "F.Paste")
			(net "GND")
		)
		(pad "3" smd rect
			(at 0 1.700022 90)
			(size 1.8034 0.508)
			(layers "F.Cu" "F.Mask" "F.Paste")
			(net "M_H_DQ<5>")
		)
		(pad "4" smd rect
			(at 0 2.549906 90)
			(size 1.8034 0.508)
			(layers "F.Cu" "F.Mask" "F.Paste")
			(net "GND")
		)
		(pad "5" smd rect
			(at 0 3.400044 90)
			(size 1.8034 0.508)
			(layers "F.Cu" "F.Mask" "F.Paste")
			(net "M_H_DQ<1>")
		)
		(pad "6" smd rect
			(at 0 4.249928 90)
			(size 1.8034 0.508)
			(layers "F.Cu" "F.Mask" "F.Paste")
			(net "GND")
		)
		(pad "7" smd rect
			(at 0 5.100066 90)
			(size 1.8034 0.508)
			(layers "F.Cu" "F.Mask" "F.Paste")
			(net "M_H_DQS_DP<9>")
		)
		(pad "8" smd rect
			(at 0 5.94995 90)
			(size 1.8034 0.508)
			(layers "F.Cu" "F.Mask" "F.Paste")
			(net "M_H_DQS_DN<9>")
		)
		(pad "9" smd rect
			(at 0 6.800088 90)
			(size 1.8034 0.508)
			(layers "F.Cu" "F.Mask" "F.Paste")
			(net "GND")
		)
		(pad "10" smd rect
			(at 0 7.649972 90)
			(size 1.8034 0.508)
			(layers "F.Cu" "F.Mask" "F.Paste")
			(net "M_H_DQ<7>")
		)
		(pad "11" smd rect
			(at 0 8.50011 90)
			(size 1.8034 0.508)
			(layers "F.Cu" "F.Mask" "F.Paste")
			(net "GND")
		)
		(pad "12" smd rect
			(at 0 9.349994 90)
			(size 1.8034 0.508)
			(layers "F.Cu" "F.Mask" "F.Paste")
			(net "M_H_DQ<3>")
		)
		(pad "13" smd rect
			(at 0 10.199878 90)
			(size 1.8034 0.508)
			(layers "F.Cu" "F.Mask" "F.Paste")
			(net "GND")
		)
		(pad "14" smd rect
			(at 0 11.050016 90)
			(size 1.8034 0.508)
			(layers "F.Cu" "F.Mask" "F.Paste")
			(net "M_H_DQ<13>")
		)
		(pad "15" smd rect
			(at 0 11.8999 90)
			(size 1.8034 0.508)
			(layers "F.Cu" "F.Mask" "F.Paste")
			(net "GND")
		)
		(pad "16" smd rect
			(at 0 12.750038 90)
			(size 1.8034 0.508)
			(layers "F.Cu" "F.Mask" "F.Paste")
			(net "M_H_DQ<9>")
		)
		(pad "17" smd rect
			(at 0 13.599922 90)
			(size 1.8034 0.508)
			(layers "F.Cu" "F.Mask" "F.Paste")
			(net "GND")
		)
		(pad "18" smd rect
			(at 0 14.45006 90)
			(size 1.8034 0.508)
			(layers "F.Cu" "F.Mask" "F.Paste")
			(net "M_H_DQS_DP<10>")
		)
		(pad "19" smd rect
			(at 0 15.299944 90)
			(size 1.8034 0.508)
			(layers "F.Cu" "F.Mask" "F.Paste")
			(net "M_H_DQS_DN<10>")
		)
		(pad "20" smd rect
			(at 0 16.150082 90)
			(size 1.8034 0.508)
			(layers "F.Cu" "F.Mask" "F.Paste")
			(net "GND")
		)
		(pad "21" smd rect
			(at 0 16.999966 90)
			(size 1.8034 0.508)
			(layers "F.Cu" "F.Mask" "F.Paste")
			(net "M_H_DQ<15>")
		)
		(pad "22" smd rect
			(at 0 17.850104 90)
			(size 1.8034 0.508)
			(layers "F.Cu" "F.Mask" "F.Paste")
			(net "GND")
		)
		(pad "23" smd rect
			(at 0 18.699988 90)
			(size 1.8034 0.508)
			(layers "F.Cu" "F.Mask" "F.Paste")
			(net "M_H_DQ<11>")
		)
		(pad "24" smd rect
			(at 0 19.550126 90)
			(size 1.8034 0.508)
			(layers "F.Cu" "F.Mask" "F.Paste")
			(net "GND")
		)
		(pad "25" smd rect
			(at 0 20.40001 90)
			(size 1.8034 0.508)
			(layers "F.Cu" "F.Mask" "F.Paste")
			(net "M_H_DQ<21>")
		)
		(pad "26" smd rect
			(at 0 21.249894 90)
			(size 1.8034 0.508)
			(layers "F.Cu" "F.Mask" "F.Paste")
			(net "GND")
		)
		(pad "27" smd rect
			(at 0 22.100032 90)
			(size 1.8034 0.508)
			(layers "F.Cu" "F.Mask" "F.Paste")
			(net "M_H_DQ<17>")
		)
		(pad "28" smd rect
			(at 0 22.949916 90)
			(size 1.8034 0.508)
			(layers "F.Cu" "F.Mask" "F.Paste")
			(net "GND")
		)
		(pad "29" smd rect
			(at 0 23.800054 90)
			(size 1.8034 0.508)
			(layers "F.Cu" "F.Mask" "F.Paste")
			(net "M_H_DQS_DP<11>")
		)
		(pad "30" smd rect
			(at 0 24.649938 90)
			(size 1.8034 0.508)
			(layers "F.Cu" "F.Mask" "F.Paste")
			(net "M_H_DQS_DN<11>")
		)
		(pad "31" smd rect
			(at 0 25.500076 90)
			(size 1.8034 0.508)
			(layers "F.Cu" "F.Mask" "F.Paste")
			(net "GND")
		)
		(pad "32" smd rect
			(at 0 26.34996 90)
			(size 1.8034 0.508)
			(layers "F.Cu" "F.Mask" "F.Paste")
			(net "M_H_DQ<23>")
		)
		(pad "33" smd rect
			(at 0 27.200098 90)
			(size 1.8034 0.508)
			(layers "F.Cu" "F.Mask" "F.Paste")
			(net "GND")
		)
		(pad "34" smd rect
			(at 0 28.049982 90)
			(size 1.8034 0.508)
			(layers "F.Cu" "F.Mask" "F.Paste")
			(net "M_H_DQ<19>")
		)
		(pad "35" smd rect
			(at 0 28.90012 90)
			(size 1.8034 0.508)
			(layers "F.Cu" "F.Mask" "F.Paste")
			(net "GND")
		)
		(pad "36" smd rect
			(at 0 29.750004 90)
			(size 1.8034 0.508)
			(layers "F.Cu" "F.Mask" "F.Paste")
			(net "M_H_DQ<29>")
		)
		(pad "37" smd rect
			(at 0 30.599888 90)
			(size 1.8034 0.508)
			(layers "F.Cu" "F.Mask" "F.Paste")
			(net "GND")
		)
		(pad "38" smd rect
			(at 0 31.450026 90)
			(size 1.8034 0.508)
			(layers "F.Cu" "F.Mask" "F.Paste")
			(net "M_H_DQ<25>")
		)
		(pad "39" smd rect
			(at 0 32.29991 90)
			(size 1.8034 0.508)
			(layers "F.Cu" "F.Mask" "F.Paste")
			(net "GND")
		)
		(pad "40" smd rect
			(at 0 33.150048 90)
			(size 1.8034 0.508)
			(layers "F.Cu" "F.Mask" "F.Paste")
			(net "M_H_DQS_DP<12>")
		)
		(pad "41" smd rect
			(at 0 33.999932 90)
			(size 1.8034 0.508)
			(layers "F.Cu" "F.Mask" "F.Paste")
			(net "M_H_DQS_DN<12>")
		)
		(pad "42" smd rect
			(at 0 34.85007 90)
			(size 1.8034 0.508)
			(layers "F.Cu" "F.Mask" "F.Paste")
			(net "GND")
		)
		(pad "43" smd rect
			(at 0 35.699954 90)
			(size 1.8034 0.508)
			(layers "F.Cu" "F.Mask" "F.Paste")
			(net "M_H_DQ<31>")
		)
		(pad "44" smd rect
			(at 0 36.550092 90)
			(size 1.8034 0.508)
			(layers "F.Cu" "F.Mask" "F.Paste")
			(net "GND")
		)
		(pad "45" smd rect
			(at 0 37.399976 90)
			(size 1.8034 0.508)
			(layers "F.Cu" "F.Mask" "F.Paste")
			(net "M_H_DQ<27>")
		)
		(pad "46" smd rect
			(at 0 38.250114 90)
			(size 1.8034 0.508)
			(layers "F.Cu" "F.Mask" "F.Paste")
			(net "GND")
		)
		(pad "47" smd rect
			(at 0 39.099998 90)
			(size 1.8034 0.508)
			(layers "F.Cu" "F.Mask" "F.Paste")
			(net "M_H_ECC<5>")
		)
		(pad "48" smd rect
			(at 0 39.949882 90)
			(size 1.8034 0.508)
			(layers "F.Cu" "F.Mask" "F.Paste")
			(net "GND")
		)
		(pad "49" smd rect
			(at 0 40.80002 90)
			(size 1.8034 0.508)
			(layers "F.Cu" "F.Mask" "F.Paste")
			(net "M_H_ECC<1>")
		)
		(pad "50" smd rect
			(at 0 41.649904 90)
			(size 1.8034 0.508)
			(layers "F.Cu" "F.Mask" "F.Paste")
			(net "GND")
		)
		(pad "51" smd rect
			(at 0 42.500042 90)
			(size 1.8034 0.508)
			(layers "F.Cu" "F.Mask" "F.Paste")
			(net "M_H_DQS_DP<17>")
		)
		(pad "52" smd rect
			(at 0 43.349926 90)
			(size 1.8034 0.508)
			(layers "F.Cu" "F.Mask" "F.Paste")
			(net "M_H_DQS_DN<17>")
		)
		(pad "53" smd rect
			(at 0 44.200064 90)
			(size 1.8034 0.508)
			(layers "F.Cu" "F.Mask" "F.Paste")
			(net "GND")
		)
		(pad "54" smd rect
			(at 0 45.049948 90)
			(size 1.8034 0.508)
			(layers "F.Cu" "F.Mask" "F.Paste")
			(net "M_H_ECC<7>")
		)
		(pad "55" smd rect
			(at 0 45.900086 90)
			(size 1.8034 0.508)
			(layers "F.Cu" "F.Mask" "F.Paste")
			(net "GND")
		)
		(pad "56" smd rect
			(at 0 46.74997 90)
			(size 1.8034 0.508)
			(layers "F.Cu" "F.Mask" "F.Paste")
			(net "M_H_ECC<3>")
		)
		(pad "57" smd rect
			(at 0 47.600108 90)
			(size 1.8034 0.508)
			(layers "F.Cu" "F.Mask" "F.Paste")
			(net "GND")
		)
		(pad "58" smd rect
			(at 0 48.449992 90)
			(size 1.8034 0.508)
			(layers "F.Cu" "F.Mask" "F.Paste")
			(net "M_GHJ_RST_N")
		)
		(pad "59" smd rect
			(at 0 49.299876 90)
			(size 1.8034 0.508)
			(layers "F.Cu" "F.Mask" "F.Paste")
			(net "PVDDQ_GHJ")
		)
		(pad "60" smd rect
			(at 0 50.150014 90)
			(size 1.8034 0.508)
			(layers "F.Cu" "F.Mask" "F.Paste")
			(net "M_H_CKE<0>")
		)
		(pad "61" smd rect
			(at 0 50.999898 90)
			(size 1.8034 0.508)
			(layers "F.Cu" "F.Mask" "F.Paste")
			(net "PVDDQ_GHJ")
		)
		(pad "62" smd rect
			(at 0 51.850036 90)
			(size 1.8034 0.508)
			(layers "F.Cu" "F.Mask" "F.Paste")
			(net "M_H_ACT_N")
		)
		(pad "63" smd rect
			(at 0 52.69992 90)
			(size 1.8034 0.508)
			(layers "F.Cu" "F.Mask" "F.Paste")
			(net "M_H_BG<0>")
		)
		(pad "64" smd rect
			(at 0 53.550058 90)
			(size 1.8034 0.508)
			(layers "F.Cu" "F.Mask" "F.Paste")
			(net "PVDDQ_GHJ")
		)
		(pad "65" smd rect
			(at 0 54.399942 90)
			(size 1.8034 0.508)
			(layers "F.Cu" "F.Mask" "F.Paste")
			(net "M_H_MA<12>")
		)
		(pad "66" smd rect
			(at 0 55.25008 90)
			(size 1.8034 0.508)
			(layers "F.Cu" "F.Mask" "F.Paste")
			(net "M_H_MA<9>")
		)
		(pad "67" smd rect
			(at 0 56.099964 90)
			(size 1.8034 0.508)
			(layers "F.Cu" "F.Mask" "F.Paste")
			(net "PVDDQ_GHJ")
		)
		(pad "68" smd rect
			(at 0 56.950102 90)
			(size 1.8034 0.508)
			(layers "F.Cu" "F.Mask" "F.Paste")
			(net "M_H_MA<8>")
		)
		(pad "69" smd rect
			(at 0 57.799986 90)
			(size 1.8034 0.508)
			(layers "F.Cu" "F.Mask" "F.Paste")
			(net "M_H_MA<6>")
		)
		(pad "70" smd rect
			(at 0 58.650124 90)
			(size 1.8034 0.508)
			(layers "F.Cu" "F.Mask" "F.Paste")
			(net "PVDDQ_GHJ")
		)
		(pad "71" smd rect
			(at 0 59.500008 90)
			(size 1.8034 0.508)
			(layers "F.Cu" "F.Mask" "F.Paste")
			(net "M_H_MA<3>")
		)
		(pad "72" smd rect
			(at 0 60.349892 90)
			(size 1.8034 0.508)
			(layers "F.Cu" "F.Mask" "F.Paste")
			(net "M_H_MA<1>")
		)
		(pad "73" smd rect
			(at 0 61.20003 90)
			(size 1.8034 0.508)
			(layers "F.Cu" "F.Mask" "F.Paste")
			(net "PVDDQ_GHJ")
		)
		(pad "74" smd rect
			(at 0 62.049914 90)
			(size 1.8034 0.508)
			(layers "F.Cu" "F.Mask" "F.Paste")
			(net "M_H_CLK_DP<0>")
		)
		(pad "75" smd rect
			(at 0 62.900052 90)
			(size 1.8034 0.508)
			(layers "F.Cu" "F.Mask" "F.Paste")
			(net "M_H_CLK_DN<0>")
		)
		(pad "76" smd rect
			(at 0 63.749936 90)
			(size 1.8034 0.508)
			(layers "F.Cu" "F.Mask" "F.Paste")
			(net "PVDDQ_GHJ")
		)
		(pad "77" smd rect
			(at 0 64.600074 90)
			(size 1.8034 0.508)
			(layers "F.Cu" "F.Mask" "F.Paste")
			(net "PVTT_GHJ")
		)
		(pad "78" smd rect
			(at 0 70.550024 90)
			(size 1.8034 0.508)
			(layers "F.Cu" "F.Mask" "F.Paste")
			(net "FM_DIMM_EVENT_COD_N")
		)
		(pad "79" smd rect
			(at 0 71.399908 90)
			(size 1.8034 0.508)
			(layers "F.Cu" "F.Mask" "F.Paste")
			(net "M_H_MA<0>")
		)
		(pad "80" smd rect
			(at 0 72.250046 90)
			(size 1.8034 0.508)
			(layers "F.Cu" "F.Mask" "F.Paste")
			(net "PVDDQ_GHJ")
		)
		(pad "81" smd rect
			(at 0 73.09993 90)
			(size 1.8034 0.508)
			(layers "F.Cu" "F.Mask" "F.Paste")
			(net "M_H_BA<0>")
		)
		(pad "82" smd rect
			(at 0 73.950068 90)
			(size 1.8034 0.508)
			(layers "F.Cu" "F.Mask" "F.Paste")
			(net "M_H_MA<16>")
		)
		(pad "83" smd rect
			(at 0 74.799952 90)
			(size 1.8034 0.508)
			(layers "F.Cu" "F.Mask" "F.Paste")
			(net "PVDDQ_GHJ")
		)
		(pad "84" smd rect
			(at 0 75.65009 90)
			(size 1.8034 0.508)
			(layers "F.Cu" "F.Mask" "F.Paste")
			(net "M_H_CS_N<0>")
		)
		(pad "85" smd rect
			(at 0 76.499974 90)
			(size 1.8034 0.508)
			(layers "F.Cu" "F.Mask" "F.Paste")
			(net "PVDDQ_GHJ")
		)
		(pad "86" smd rect
			(at 0 77.350112 90)
			(size 1.8034 0.508)
			(layers "F.Cu" "F.Mask" "F.Paste")
			(net "M_H_MA<15>")
		)
		(pad "87" smd rect
			(at 0 78.199996 90)
			(size 1.8034 0.508)
			(layers "F.Cu" "F.Mask" "F.Paste")
			(net "M_H_ODT<0>")
		)
		(pad "88" smd rect
			(at 0 79.04988 90)
			(size 1.8034 0.508)
			(layers "F.Cu" "F.Mask" "F.Paste")
			(net "PVDDQ_GHJ")
		)
		(pad "89" smd rect
			(at 0 79.900018 90)
			(size 1.8034 0.508)
			(layers "F.Cu" "F.Mask" "F.Paste")
			(net "M_H_CS_N<1>")
		)
		(pad "90" smd rect
			(at 0 80.749902 90)
			(size 1.8034 0.508)
			(layers "F.Cu" "F.Mask" "F.Paste")
			(net "PVDDQ_GHJ")
		)
		(pad "91" smd rect
			(at 0 81.60004 90)
			(size 1.8034 0.508)
			(layers "F.Cu" "F.Mask" "F.Paste")
			(net "M_H_ODT<1>")
		)
		(pad "92" smd rect
			(at 0 82.449924 90)
			(size 1.8034 0.508)
			(layers "F.Cu" "F.Mask" "F.Paste")
			(net "PVDDQ_GHJ")
		)
		(pad "93" smd rect
			(at 0 83.300062 90)
			(size 1.8034 0.508)
			(layers "F.Cu" "F.Mask" "F.Paste")
			(net "M_H_CS_N<2>")
		)
		(pad "94" smd rect
			(at 0 84.149946 90)
			(size 1.8034 0.508)
			(layers "F.Cu" "F.Mask" "F.Paste")
			(net "GND")
		)
		(pad "95" smd rect
			(at 0 85.000084 90)
			(size 1.8034 0.508)
			(layers "F.Cu" "F.Mask" "F.Paste")
			(net "M_H_DQ<37>")
		)
		(pad "96" smd rect
			(at 0 85.849968 90)
			(size 1.8034 0.508)
			(layers "F.Cu" "F.Mask" "F.Paste")
			(net "GND")
		)
		(pad "97" smd rect
			(at 0 86.700106 90)
			(size 1.8034 0.508)
			(layers "F.Cu" "F.Mask" "F.Paste")
			(net "M_H_DQ<33>")
		)
		(pad "98" smd rect
			(at 0 87.54999 90)
			(size 1.8034 0.508)
			(layers "F.Cu" "F.Mask" "F.Paste")
			(net "GND")
		)
		(pad "99" smd rect
			(at 0 88.399874 90)
			(size 1.8034 0.508)
			(layers "F.Cu" "F.Mask" "F.Paste")
			(net "M_H_DQS_DP<13>")
		)
		(pad "100" smd rect
			(at 0 89.250012 90)
			(size 1.8034 0.508)
			(layers "F.Cu" "F.Mask" "F.Paste")
			(net "M_H_DQS_DN<13>")
		)
		(pad "101" smd rect
			(at 0 90.099896 90)
			(size 1.8034 0.508)
			(layers "F.Cu" "F.Mask" "F.Paste")
			(net "GND")
		)
		(pad "102" smd rect
			(at 0 90.950034 90)
			(size 1.8034 0.508)
			(layers "F.Cu" "F.Mask" "F.Paste")
			(net "M_H_DQ<39>")
		)
		(pad "103" smd rect
			(at 0 91.799918 90)
			(size 1.8034 0.508)
			(layers "F.Cu" "F.Mask" "F.Paste")
			(net "GND")
		)
		(pad "104" smd rect
			(at 0 92.650056 90)
			(size 1.8034 0.508)
			(layers "F.Cu" "F.Mask" "F.Paste")
			(net "M_H_DQ<35>")
		)
		(pad "105" smd rect
			(at 0 93.49994 90)
			(size 1.8034 0.508)
			(layers "F.Cu" "F.Mask" "F.Paste")
			(net "GND")
		)
		(pad "106" smd rect
			(at 0 94.350078 90)
			(size 1.8034 0.508)
			(layers "F.Cu" "F.Mask" "F.Paste")
			(net "M_H_DQ<45>")
		)
		(pad "107" smd rect
			(at 0 95.199962 90)
			(size 1.8034 0.508)
			(layers "F.Cu" "F.Mask" "F.Paste")
			(net "GND")
		)
		(pad "108" smd rect
			(at 0 96.0501 90)
			(size 1.8034 0.508)
			(layers "F.Cu" "F.Mask" "F.Paste")
			(net "M_H_DQ<41>")
		)
		(pad "109" smd rect
			(at 0 96.899984 90)
			(size 1.8034 0.508)
			(layers "F.Cu" "F.Mask" "F.Paste")
			(net "GND")
		)
		(pad "110" smd rect
			(at 0 97.750122 90)
			(size 1.8034 0.508)
			(layers "F.Cu" "F.Mask" "F.Paste")
			(net "M_H_DQS_DP<14>")
		)
		(pad "111" smd rect
			(at 0 98.600006 90)
			(size 1.8034 0.508)
			(layers "F.Cu" "F.Mask" "F.Paste")
			(net "M_H_DQS_DN<14>")
		)
		(pad "112" smd rect
			(at 0 99.44989 90)
			(size 1.8034 0.508)
			(layers "F.Cu" "F.Mask" "F.Paste")
			(net "GND")
		)
		(pad "113" smd rect
			(at 0 100.300028 90)
			(size 1.8034 0.508)
			(layers "F.Cu" "F.Mask" "F.Paste")
			(net "M_H_DQ<47>")
		)
		(pad "114" smd rect
			(at 0 101.149912 90)
			(size 1.8034 0.508)
			(layers "F.Cu" "F.Mask" "F.Paste")
			(net "GND")
		)
		(pad "115" smd rect
			(at 0 102.00005 90)
			(size 1.8034 0.508)
			(layers "F.Cu" "F.Mask" "F.Paste")
			(net "M_H_DQ<43>")
		)
		(pad "116" smd rect
			(at 0 102.849934 90)
			(size 1.8034 0.508)
			(layers "F.Cu" "F.Mask" "F.Paste")
			(net "GND")
		)
		(pad "117" smd rect
			(at 0 103.700072 90)
			(size 1.8034 0.508)
			(layers "F.Cu" "F.Mask" "F.Paste")
			(net "M_H_DQ<53>")
		)
		(pad "118" smd rect
			(at 0 104.549956 90)
			(size 1.8034 0.508)
			(layers "F.Cu" "F.Mask" "F.Paste")
			(net "GND")
		)
		(pad "119" smd rect
			(at 0 105.400094 90)
			(size 1.8034 0.508)
			(layers "F.Cu" "F.Mask" "F.Paste")
			(net "M_H_DQ<49>")
		)
		(pad "120" smd rect
			(at 0 106.249978 90)
			(size 1.8034 0.508)
			(layers "F.Cu" "F.Mask" "F.Paste")
			(net "GND")
		)
	)
)
